(kicad_pcb
	(version 20241229)
	(generator "pcbnew")
	(generator_version "9.0")
	(general
		(thickness 1.6642)
		(legacy_teardrops no)
	)
	(paper "A3")
	(title_block
		(title "PolarFire SoM")
		(date "2025-07-22")
		(rev "1.1.4")
		(company "Antmicro Ltd")
		(comment 1 "www.antmicro.com")
		(comment 9 "footprint 85 of 470 (U1), pads 1-67 of 484")
	)
	(layers
		(0 "F.Cu" mixed)
		(4 "In1.Cu" power)
		(6 "In2.Cu" signal)
		(8 "In3.Cu" power)
		(10 "In4.Cu" signal)
		(12 "In5.Cu" power)
		(14 "In6.Cu" power)
		(16 "In7.Cu" signal)
		(18 "In8.Cu" power)
		(20 "In9.Cu" signal)
		(22 "In10.Cu" power)
		(24 "In11.Cu" signal)
		(26 "In12.Cu" signal)
		(2 "B.Cu" mixed)
		(9 "F.Adhes" user "F.Adhesive")
		(11 "B.Adhes" user "B.Adhesive")
		(13 "F.Paste" user)
		(15 "B.Paste" user)
		(5 "F.SilkS" user "F.Silkscreen")
		(7 "B.SilkS" user "B.Silkscreen")
		(1 "F.Mask" user)
		(3 "B.Mask" user)
		(17 "Dwgs.User" user "User.Drawings")
		(19 "Cmts.User" user "User.Comments")
		(21 "Eco1.User" user "User.Eco1")
		(23 "Eco2.User" user "User.Eco2")
		(25 "Edge.Cuts" user)
		(27 "Margin" user)
		(31 "F.CrtYd" user "F.Courtyard")
		(29 "B.CrtYd" user "B.Courtyard")
		(35 "F.Fab" user)
		(33 "B.Fab" user)
	)
	(footprint "antmicro-footprints:BGA-484_19x19mm_Layout22x22_P0.8mm_FCVG484"
		(layer "F.Cu")
		(at 197.699 132.701 -90)
		(descr "FCVG484, 19.0x19.0mm, 484 Ball, 22x22 Layout, 0.8mm Pitch")
		(tags "BGA 484 0.8")
		(property "Reference" "U1"
			(at 0 -10.8 270)
			(layer "F.SilkS")
			(effects
				(font
					(size 0.7 0.7)
					(thickness 0.15)
				)
				(justify left bottom)
			)
		)
		(property "Value" "MPFS250T-FCVG484"
			(at 0 11.5 270)
			(layer "F.Fab")
			(hide yes)
			(effects
				(font
					(size 0.7 0.7)
					(thickness 0.15)
				)
				(justify left bottom)
			)
		)
		(property "Datasheet" "https://ww1.microchip.com/downloads/aemDocuments/documents/FPGA/ProductDocuments/DataSheets/PolarFire-SoC-Datasheet-DS00004248.pdf"
			(at 0 0 270)
			(layer "F.Fab")
			(hide yes)
			(effects
				(font
					(size 1.27 1.27)
					(thickness 0.15)
				)
			)
		)
		(property "Description" "RISC-V System On Chip (SOC) IC PolarFire® FPGA - 254K Logic Modules 484-FCBGA (19x19)"
			(at 0 0 270)
			(layer "F.Fab")
			(hide yes)
			(effects
				(font
					(size 1.27 1.27)
					(thickness 0.15)
				)
			)
		)
		(property "MPN" "MPFS250T-FCVG484E"
			(at 0 0 270)
			(unlocked yes)
			(layer "F.Fab")
			(hide yes)
			(effects
				(font
					(size 1 1)
					(thickness 0.15)
				)
			)
		)
		(property "Manufacturer" "Microchip Technology"
			(at 0 0 270)
			(unlocked yes)
			(layer "F.Fab")
			(hide yes)
			(effects
				(font
					(size 1 1)
					(thickness 0.15)
				)
			)
		)
		(property "VSD_class" "MPFS250T"
			(at 0 0 270)
			(unlocked yes)
			(layer "F.Fab")
			(hide yes)
			(effects
				(font
					(size 1 1)
					(thickness 0.15)
				)
			)
		)
		(property "Author" "Antmicro"
			(at 0 0 270)
			(unlocked yes)
			(layer "F.Fab")
			(hide yes)
			(effects
				(font
					(size 1 1)
					(thickness 0.15)
				)
			)
		)
		(property "License" "Apache-2.0"
			(at 0 0 270)
			(unlocked yes)
			(layer "F.Fab")
			(hide yes)
			(effects
				(font
					(size 1 1)
					(thickness 0.15)
				)
			)
		)
		(sheetname "/FPGA Config/")
		(sheetfile "fpga-config.kicad_sch")
		(attr smd)
		(pad "A1" smd circle
			(at -8.401 -8.401 270)
			(size 0.45 0.45)
			(layers "F.Cu" "F.Mask" "F.Paste")
			(net 417 "GND")
			(pinfunction "VSS")
			(pintype "passive")
		)
		(pad "A2" smd circle
			(at -7.6 -8.401 270)
			(size 0.45 0.45)
			(layers "F.Cu" "F.Mask" "F.Paste")
			(net 357 "unconnected-(U1C-MSSIO33B2-PadA2)")
			(pinfunction "MSSIO33B2")
			(pintype "bidirectional+no_connect")
			(die_length 11.723)
		)
		(pad "A3" smd circle
			(at -6.8 -8.401 270)
			(size 0.45 0.45)
			(layers "F.Cu" "F.Mask" "F.Paste")
			(net 285 "Net-(U1C-MSSIO35B2)")
			(pinfunction "MSSIO35B2")
			(pintype "bidirectional")
			(die_length 11.2271)
		)
		(pad "A4" smd circle
			(at -6 -8.401 270)
			(size 0.45 0.45)
			(layers "F.Cu" "F.Mask" "F.Paste")
			(net 417 "GND")
			(pinfunction "VSS")
			(pintype "passive")
		)
		(pad "A5" smd circle
			(at -5.201 -8.401 270)
			(size 0.45 0.45)
			(layers "F.Cu" "F.Mask" "F.Paste")
			(net 334 "VREF_FLAG")
			(pinfunction "GPIO172NB1")
			(pintype "bidirectional")
			(die_length 6.59962)
		)
		(pad "A6" smd circle
			(at -4.401 -8.401 270)
			(size 0.45 0.45)
			(layers "F.Cu" "F.Mask" "F.Paste")
			(net 135 "UART3_TX{slash}RPI_GPIO04")
			(pinfunction "GPIO172PB1/CCC_SW_PLL1_OUT1")
			(pintype "bidirectional")
			(die_length 6.56707)
		)
		(pad "A7" smd circle
			(at -3.601 -8.401 270)
			(size 0.45 0.45)
			(layers "F.Cu" "F.Mask" "F.Paste")
			(net 173 "UART0_TX{slash}RPI_GPIO14")
			(pinfunction "GPIO173PB1/CLKIN_S_3/CCC_SW_CLKIN_S_3")
			(pintype "bidirectional")
			(die_length 6.40706)
		)
		(pad "A8" smd circle
			(at -2.8 -8.401 270)
			(size 0.45 0.45)
			(layers "F.Cu" "F.Mask" "F.Paste")
			(net 348 "/FPGA GPIO/HDMI0_SDA_SRC")
			(pinfunction "GPIO175PB1")
			(pintype "bidirectional")
			(die_length 6.73131)
		)
		(pad "A9" smd circle
			(at -2 -8.401 270)
			(size 0.45 0.45)
			(layers "F.Cu" "F.Mask" "F.Paste")
			(net 649 "VDD")
			(pinfunction "VDDI1")
			(pintype "passive")
		)
		(pad "A10" smd circle
			(at -1.2 -8.401 270)
			(size 0.45 0.45)
			(layers "F.Cu" "F.Mask" "F.Paste")
			(net 359 "unconnected-(U1B-GPIO177PB1{slash}CCC_SW_PLL0_OUT0-PadA10)")
			(pinfunction "GPIO177PB1/CCC_SW_PLL0_OUT0")
			(pintype "bidirectional+no_connect")
			(die_length 7.84164)
		)
		(pad "A11" smd circle
			(at -0.401 -8.401 270)
			(size 0.45 0.45)
			(layers "F.Cu" "F.Mask" "F.Paste")
			(net 558 "unconnected-(U1B-GPIO177NB1-PadA11)")
			(pinfunction "GPIO177NB1")
			(pintype "bidirectional+no_connect")
			(die_length 7.8195)
		)
		(pad "A12" smd circle
			(at 0.4 -8.401 270)
			(size 0.45 0.45)
			(layers "F.Cu" "F.Mask" "F.Paste")
			(net 113 "/Bottom Connector/CAM0.D1_N")
			(pinfunction "GPIO1NB1")
			(pintype "bidirectional")
			(die_length 7.19699)
		)
		(pad "A13" smd circle
			(at 1.199 -8.401 270)
			(size 0.45 0.45)
			(layers "F.Cu" "F.Mask" "F.Paste")
			(net 115 "/Bottom Connector/CAM0.D1_P")
			(pinfunction "GPIO1PB1/CLKIN_S_5")
			(pintype "bidirectional")
			(die_length 7.21046)
		)
		(pad "A14" smd circle
			(at 1.999 -8.401 270)
			(size 0.45 0.45)
			(layers "F.Cu" "F.Mask" "F.Paste")
			(net 417 "GND")
			(pinfunction "VSS")
			(pintype "passive")
		)
		(pad "A15" smd circle
			(at 2.799 -8.401 270)
			(size 0.45 0.45)
			(layers "F.Cu" "F.Mask" "F.Paste")
			(net 344 "/FPGA GPIO/PF_ETH_MDC")
			(pinfunction "GPIO5PB1/CLKIN_S_7")
			(pintype "bidirectional")
			(die_length 7.65884)
		)
		(pad "A16" smd circle
			(at 3.6 -8.401 270)
			(size 0.45 0.45)
			(layers "F.Cu" "F.Mask" "F.Paste")
			(net 30 "UART3_RX{slash}RPI_GPIO05")
			(pinfunction "GPIO13PB1")
			(pintype "bidirectional")
			(die_length 10.4183)
		)
		(pad "A17" smd circle
			(at 4.4 -8.401 270)
			(size 0.45 0.45)
			(layers "F.Cu" "F.Mask" "F.Paste")
			(net 12 "GPIO6")
			(pinfunction "GPIO13NB1")
			(pintype "bidirectional")
			(die_length 10.3918)
		)
		(pad "A18" smd circle
			(at 5.2 -8.401 270)
			(size 0.45 0.45)
			(layers "F.Cu" "F.Mask" "F.Paste")
			(net 8 "GPIO26")
			(pinfunction "GPIO17PB1/CCC_SE_CLKIN_S_11")
			(pintype "bidirectional")
			(die_length 10.8908)
		)
		(pad "A19" smd circle
			(at 5.999 -8.401 270)
			(size 0.45 0.45)
			(layers "F.Cu" "F.Mask" "F.Paste")
			(net 649 "VDD")
			(pinfunction "VDDI1")
			(pintype "power_in")
		)
		(pad "A20" smd circle
			(at 6.799 -8.401 270)
			(size 0.45 0.45)
			(layers "F.Cu" "F.Mask" "F.Paste")
			(net 351 "/FPGA GPIO/WiFi_DATA_3")
			(pinfunction "GPIO20PB9/DQS")
			(pintype "bidirectional")
			(die_length 10.6967)
		)
		(pad "A21" smd circle
			(at 7.599 -8.401 270)
			(size 0.45 0.45)
			(layers "F.Cu" "F.Mask" "F.Paste")
			(net 352 "/FPGA GPIO/WiFi_CLK")
			(pinfunction "GPIO20NB9/DQS")
			(pintype "bidirectional")
			(die_length 10.6945)
		)
		(pad "A22" smd circle
			(at 8.4 -8.401 270)
			(size 0.45 0.45)
			(layers "F.Cu" "F.Mask" "F.Paste")
			(net 417 "GND")
			(pinfunction "VSS")
			(pintype "passive")
		)
		(pad "AA1" smd circle
			(at -8.401 7.599 270)
			(size 0.45 0.45)
			(layers "F.Cu" "F.Mask" "F.Paste")
			(net 305 "/FPGA MSS/LPDDR4.DQ3")
			(pinfunction "MSS_DDR_DQ3")
			(pintype "bidirectional")
			(die_length 6.09637)
		)
		(pad "AA2" smd circle
			(at -7.6 7.599 270)
			(size 0.45 0.45)
			(layers "F.Cu" "F.Mask" "F.Paste")
			(net 306 "/FPGA MSS/LPDDR4.DQS0_P")
			(pinfunction "MSS_DDR_DQS_P0")
			(pintype "bidirectional")
			(die_length 6.03691)
		)
		(pad "AA3" smd circle
			(at -6.8 7.599 270)
			(size 0.45 0.45)
			(layers "F.Cu" "F.Mask" "F.Paste")
			(net 307 "/FPGA MSS/LPDDR4.DQS0_N")
			(pinfunction "MSS_DDR_DQS_N0")
			(pintype "bidirectional")
			(die_length 6.04366)
		)
		(pad "AA4" smd circle
			(at -6 7.599 270)
			(size 0.45 0.45)
			(layers "F.Cu" "F.Mask" "F.Paste")
			(net 417 "GND")
			(pinfunction "VSS")
			(pintype "passive")
		)
		(pad "AA5" smd circle
			(at -5.201 7.599 270)
			(size 0.45 0.45)
			(layers "F.Cu" "F.Mask" "F.Paste")
			(net 308 "/FPGA MSS/LPDDR4.DQ5")
			(pinfunction "MSS_DDR_DQ5")
			(pintype "bidirectional")
			(die_length 5.44591)
		)
		(pad "AA6" smd circle
			(at -4.401 7.599 270)
			(size 0.45 0.45)
			(layers "F.Cu" "F.Mask" "F.Paste")
			(net 309 "/FPGA MSS/LPDDR4.DQ11")
			(pinfunction "MSS_DDR_DQ11")
			(pintype "bidirectional")
			(die_length 6.62748)
		)
		(pad "AA7" smd circle
			(at -3.601 7.599 270)
			(size 0.45 0.45)
			(layers "F.Cu" "F.Mask" "F.Paste")
			(net 310 "/FPGA MSS/LPDDR4.DMI1")
			(pinfunction "MSS_DDR_DM1")
			(pintype "bidirectional")
			(die_length 6.55419)
		)
		(pad "AA8" smd circle
			(at -2.8 7.599 270)
			(size 0.45 0.45)
			(layers "F.Cu" "F.Mask" "F.Paste")
			(net 311 "/FPGA MSS/LPDDR4.DQ15")
			(pinfunction "MSS_DDR_DQ15")
			(pintype "bidirectional")
			(die_length 6.33971)
		)
		(pad "AA9" smd circle
			(at -2 7.599 270)
			(size 0.45 0.45)
			(layers "F.Cu" "F.Mask" "F.Paste")
			(net 2 "+1V1")
			(pinfunction "VDDI6")
			(pintype "power_in")
		)
		(pad "AA10" smd circle
			(at -1.2 7.599 270)
			(size 0.45 0.45)
			(layers "F.Cu" "F.Mask" "F.Paste")
			(net 312 "/FPGA MSS/LPDDR4.DQS2_N")
			(pinfunction "MSS_DDR_DQS_N2")
			(pintype "bidirectional")
			(die_length 8.02694)
		)
		(pad "AA11" smd circle
			(at -0.401 7.599 270)
			(size 0.45 0.45)
			(layers "F.Cu" "F.Mask" "F.Paste")
			(net 313 "/FPGA MSS/LPDDR4.DQS2_P")
			(pinfunction "MSS_DDR_DQS_P2")
			(pintype "bidirectional")
			(die_length 8.03866)
		)
		(pad "AA12" smd circle
			(at 0.4 7.599 270)
			(size 0.45 0.45)
			(layers "F.Cu" "F.Mask" "F.Paste")
			(net 360 "unconnected-(U1A-HSIO88PB0-PadAA12)")
			(pinfunction "HSIO88PB0")
			(pintype "bidirectional+no_connect")
			(die_length 6.6173)
		)
		(pad "AA13" smd circle
			(at 1.199 7.599 270)
			(size 0.45 0.45)
			(layers "F.Cu" "F.Mask" "F.Paste")
			(net 361 "unconnected-(U1A-HSIO86PB0{slash}CLKIN_N_4{slash}CCC_NW_PLL0_OUT0-PadAA13)")
			(pinfunction "HSIO86PB0/CLKIN_N_4/CCC_NW_PLL0_OUT0")
			(pintype "bidirectional+no_connect")
			(die_length 6.19556)
		)
		(pad "AA14" smd circle
			(at 1.999 7.599 270)
			(size 0.45 0.45)
			(layers "F.Cu" "F.Mask" "F.Paste")
			(net 417 "GND")
			(pinfunction "VSS")
			(pintype "passive")
		)
		(pad "AA15" smd circle
			(at 2.799 7.599 270)
			(size 0.45 0.45)
			(layers "F.Cu" "F.Mask" "F.Paste")
			(net 362 "unconnected-(U1A-HSIO85NB0-PadAA15)")
			(pinfunction "HSIO85NB0")
			(pintype "bidirectional+no_connect")
			(die_length 5.45513)
		)
		(pad "AA16" smd circle
			(at 3.6 7.599 270)
			(size 0.45 0.45)
			(layers "F.Cu" "F.Mask" "F.Paste")
			(net 363 "unconnected-(U1A-HSIO82PB0-PadAA16)")
			(pinfunction "HSIO82PB0")
			(pintype "bidirectional+no_connect")
			(die_length 6.6422)
		)
		(pad "AA17" smd circle
			(at 4.4 7.599 270)
			(size 0.45 0.45)
			(layers "F.Cu" "F.Mask" "F.Paste")
			(net 364 "unconnected-(U1A-HSIO81NB0{slash}DQS-PadAA17)")
			(pinfunction "HSIO81NB0/DQS")
			(pintype "bidirectional+no_connect")
			(die_length 6.85921)
		)
		(pad "AA18" smd circle
			(at 5.2 7.599 270)
			(size 0.45 0.45)
			(layers "F.Cu" "F.Mask" "F.Paste")
			(net 130 "/FPGA HSIO/Crosslink_B2.D6")
			(pinfunction "HSIO78NB0")
			(pintype "bidirectional")
			(die_length 5.90226)
		)
		(pad "AA19" smd circle
			(at 5.999 7.599 270)
			(size 0.45 0.45)
			(layers "F.Cu" "F.Mask" "F.Paste")
			(net 48 "+1V8")
			(pinfunction "VDDI0")
			(pintype "power_in")
		)
		(pad "AA20" smd circle
			(at 6.799 7.599 270)
			(size 0.45 0.45)
			(layers "F.Cu" "F.Mask" "F.Paste")
			(net 131 "/FPGA HSIO/Crosslink_B2.D2")
			(pinfunction "HSIO71NB0")
			(pintype "bidirectional")
			(die_length 6.7924)
		)
		(pad "AA21" smd circle
			(at 7.599 7.599 270)
			(size 0.45 0.45)
			(layers "F.Cu" "F.Mask" "F.Paste")
			(net 365 "unconnected-(U1A-HSIO69PB0{slash}DQS{slash}CCC_NE_PLL0_OUT0-PadAA21)")
			(pinfunction "HSIO69PB0/DQS/CCC_NE_PLL0_OUT0")
			(pintype "bidirectional+no_connect")
			(die_length 7.08107)
		)
		(pad "AA22" smd circle
			(at 8.4 7.599 270)
			(size 0.45 0.45)
			(layers "F.Cu" "F.Mask" "F.Paste")
			(net 136 "/FPGA HSIO/Crosslink_B2.D5")
			(pinfunction "HSIO69NB0/DQS")
			(pintype "bidirectional")
			(die_length 7.0736)
		)
		(pad "AB1" smd circle
			(at -8.401 8.4 270)
			(size 0.45 0.45)
			(layers "F.Cu" "F.Mask" "F.Paste")
			(net 417 "GND")
			(pinfunction "VSS")
			(pintype "passive")
		)
		(pad "AB2" smd circle
			(at -7.6 8.4 270)
			(size 0.45 0.45)
			(layers "F.Cu" "F.Mask" "F.Paste")
			(net 316 "/FPGA MSS/LPDDR4.DQ6")
			(pinfunction "MSS_DDR_DQ6")
			(pintype "bidirectional")
			(die_length 6.33626)
		)
		(pad "AB3" smd circle
			(at -6.8 8.4 270)
			(size 0.45 0.45)
			(layers "F.Cu" "F.Mask" "F.Paste")
			(net 319 "/FPGA MSS/LPDDR4.DQ7")
			(pinfunction "MSS_DDR_DQ7")
			(pintype "bidirectional")
			(die_length 5.58315)
		)
		(pad "AB4" smd circle
			(at -6 8.4 270)
			(size 0.45 0.45)
			(layers "F.Cu" "F.Mask" "F.Paste")
			(net 320 "/FPGA MSS/LPDDR4.DMI0")
			(pinfunction "MSS_DDR_DM0")
			(pintype "bidirectional")
			(die_length 5.56141)
		)
		(pad "AB5" smd circle
			(at -5.201 8.4 270)
			(size 0.45 0.45)
			(layers "F.Cu" "F.Mask" "F.Paste")
			(net 321 "/FPGA MSS/LPDDR4.DQ10")
			(pinfunction "MSS_DDR_DQ10")
			(pintype "bidirectional")
			(die_length 6.67168)
		)
		(pad "AB6" smd circle
			(at -4.401 8.4 270)
			(size 0.45 0.45)
			(layers "F.Cu" "F.Mask" "F.Paste")
			(net 2 "+1V1")
			(pinfunction "VDDI6")
			(pintype "passive")
		)
		(pad "AB7" smd circle
			(at -3.601 8.4 270)
			(size 0.45 0.45)
			(layers "F.Cu" "F.Mask" "F.Paste")
			(net 322 "/FPGA MSS/LPDDR4.DQ12")
			(pinfunction "MSS_DDR_DQ12")
			(pintype "bidirectional")
			(die_length 7.08953)
		)
		(pad "AB8" smd circle
			(at -2.8 8.4 270)
			(size 0.45 0.45)
			(layers "F.Cu" "F.Mask" "F.Paste")
			(net 323 "/FPGA MSS/LPDDR4.DQ13")
			(pinfunction "MSS_DDR_DQ13")
			(pintype "bidirectional")
			(die_length 6.89642)
		)
		(pad "AB9" smd circle
			(at -2 8.4 270)
			(size 0.45 0.45)
			(layers "F.Cu" "F.Mask" "F.Paste")
			(net 324 "/FPGA MSS/LPDDR4.DQ18")
			(pinfunction "MSS_DDR_DQ18")
			(pintype "bidirectional")
			(die_length 7.07175)
		)
		(pad "AB10" smd circle
			(at -1.2 8.4 270)
			(size 0.45 0.45)
			(layers "F.Cu" "F.Mask" "F.Paste")
			(net 326 "/FPGA MSS/LPDDR4.DQ19")
			(pinfunction "MSS_DDR_DQ19")
			(pintype "bidirectional")
			(die_length 7.08818)
		)
		(pad "AB11" smd circle
			(at -0.401 8.4 270)
			(size 0.45 0.45)
			(layers "F.Cu" "F.Mask" "F.Paste")
			(net 417 "GND")
			(pinfunction "VSS")
			(pintype "passive")
		)
		(pad "AB12" smd circle
			(at 0.4 8.4 270)
			(size 0.45 0.45)
			(layers "F.Cu" "F.Mask" "F.Paste")
			(net 366 "unconnected-(U1A-HSIO88NB0-PadAB12)")
			(pinfunction "HSIO88NB0")
			(pintype "bidirectional+no_connect")
			(die_length 6.62943)
		)
		(pad "AB13" smd circle
			(at 1.199 8.4 270)
			(size 0.45 0.45)
			(layers "F.Cu" "F.Mask" "F.Paste")
			(net 367 "unconnected-(U1A-HSIO86NB0-PadAB13)")
			(pinfunction "HSIO86NB0")
			(pintype "bidirectional+no_connect")
			(die_length 6.18996)
		)
		(pad "AB14" smd circle
			(at 1.999 8.4 270)
			(size 0.45 0.45)
			(layers "F.Cu" "F.Mask" "F.Paste")
			(net 368 "unconnected-(U1A-HSIO84PB0{slash}CLKIN_N_5-PadAB14)")
			(pinfunction "HSIO84PB0/CLKIN_N_5")
			(pintype "bidirectional+no_connect")
			(die_length 5.95763)
		)
		(pad "AB15" smd circle
			(at 2.799 8.4 270)
			(size 0.45 0.45)
			(layers "F.Cu" "F.Mask" "F.Paste")
			(net 369 "unconnected-(U1A-HSIO84NB0-PadAB15)")
			(pinfunction "HSIO84NB0")
			(pintype "bidirectional+no_connect")
			(die_length 5.94946)
		)
		(pad "AB16" smd circle
			(at 3.6 8.4 270)
			(size 0.45 0.45)
			(layers "F.Cu" "F.Mask" "F.Paste")
			(net 48 "+1V8")
			(pinfunction "VDDI0")
			(pintype "passive")
		)
		(pad "AB17" smd circle
			(at 4.4 8.4 270)
			(size 0.45 0.45)
			(layers "F.Cu" "F.Mask" "F.Paste")
			(net 370 "unconnected-(U1A-HSIO81PB0{slash}DQS-PadAB17)")
			(pinfunction "HSIO81PB0/DQS")
			(pintype "bidirectional+no_connect")
			(die_length 6.85682)
		)
		(pad "AB18" smd circle
			(at 5.2 8.4 270)
			(size 0.45 0.45)
			(layers "F.Cu" "F.Mask" "F.Paste")
			(net 145 "/FPGA HSIO/Crosslink_B2.D9")
			(pinfunction "HSIO78PB0/CLKIN_N_7")
			(pintype "bidirectional")
			(die_length 5.89156)
		)
		(pad "AB19" smd circle
			(at 5.999 8.4 270)
			(size 0.45 0.45)
			(layers "F.Cu" "F.Mask" "F.Paste")
			(net 154 "/FPGA HSIO/Crosslink_B2.D4")
			(pinfunction "HSIO70PB0")
			(pintype "bidirectional")
			(die_length 6.78063)
		)
		(pad "AB20" smd circle
			(at 6.799 8.4 270)
			(size 0.45 0.45)
			(layers "F.Cu" "F.Mask" "F.Paste")
			(net 210 "/FPGA HSIO/Crosslink_B2.D3")
			(pinfunction "HSIO70NB0")
			(pintype "bidirectional")
			(die_length 6.76848)
		)
		(pad "AB21" smd circle
			(at 7.599 8.4 270)
			(size 0.45 0.45)
			(layers "F.Cu" "F.Mask" "F.Paste")
			(net 223 "/FPGA HSIO/Crosslink_B2.D0")
			(pinfunction "HSIO71PB0")
			(pintype "bidirectional")
			(die_length 6.81909)
		)
		(pad "AB22" smd circle
			(at 8.4 8.4 270)
			(size 0.45 0.45)
			(layers "F.Cu" "F.Mask" "F.Paste")
			(net 417 "GND")
			(pinfunction "VSS")
			(pintype "passive")
		)
		(pad "B1" smd circle
			(at -8.401 -7.6 270)
			(size 0.45 0.45)
			(layers "F.Cu" "F.Mask" "F.Paste")
			(net 100 "/FPGA MSSIO/SUPPLY.SDA")
			(pinfunction "MSSIO27B2")
			(pintype "bidirectional")
			(die_length 11.6754)
		)
	)
)
